(kicad_pcb
	(version 20241229)
	(generator "pcbnew")
	(generator_version "9.0")
	(general
		(thickness 1.61)
		(legacy_teardrops no)
	)
	(paper "A3")
	(title_block
		(title "RDIMM DDR5 Tester")
		(date "2026-05-21")
		(rev "2.2.0")
		(company "Antmicro")
		(comment 9 "footprints 641-645 of 796")
	)
	(layers
		(0 "F.Cu" signal)
		(4 "In1.Cu" power)
		(6 "In2.Cu" mixed)
		(8 "In3.Cu" power)
		(10 "In4.Cu" mixed)
		(12 "In5.Cu" power)
		(14 "In6.Cu" mixed)
		(16 "In7.Cu" power)
		(18 "In8.Cu" power)
		(20 "In9.Cu" mixed)
		(22 "In10.Cu" power)
		(2 "B.Cu" signal)
		(9 "F.Adhes" user "F.Adhesive")
		(11 "B.Adhes" user "B.Adhesive")
		(13 "F.Paste" user)
		(15 "B.Paste" user)
		(5 "F.SilkS" user "F.Silkscreen")
		(7 "B.SilkS" user "B.Silkscreen")
		(1 "F.Mask" user)
		(3 "B.Mask" user)
		(17 "Dwgs.User" user "User.Drawings")
		(19 "Cmts.User" user "User.Comments")
		(21 "Eco1.User" user "User.Eco1")
		(23 "Eco2.User" user "User.Eco2")
		(25 "Edge.Cuts" user)
		(27 "Margin" user)
		(31 "F.CrtYd" user "F.Courtyard")
		(29 "B.CrtYd" user "B.Courtyard")
		(35 "F.Fab" user)
		(33 "B.Fab" user)
	)
	(footprint "antmicro-footprints:C_0402_1005Metric_EIA"
		(layer "B.Cu")
		(at 194 146.499 90)
		(descr "Capacitor SMD 0402 (1005 Metric), square (rectangular) end terminal, IPC_7351 nominal, (Body size source: IPC-SM-782 page 76, https://www.pcb-3d.com/wordpress/wp-content/uploads/ipc-sm-782a_amendment_1_and_2.pdf)")
		(tags "capacitor 0402")
		(property "Reference" "C334"
			(at 13.199 -30.6 270)
			(layer "B.SilkS")
			(effects
				(font
					(size 0.7 0.7)
					(thickness 0.15)
				)
				(justify left bottom mirror)
			)
		)
		(property "Value" "C_100n_0402"
			(at 0 -1.169 270)
			(layer "B.Fab")
			(effects
				(font
					(size 0.7 0.7)
					(thickness 0.15)
				)
				(justify left bottom mirror)
			)
		)
		(property "Manufacturer" "Murata"
			(at 0 0 90)
			(unlocked yes)
			(layer "B.Fab")
			(hide yes)
			(effects
				(font
					(size 1 1)
					(thickness 0.15)
				)
				(justify mirror)
			)
		)
		(property "MPN" "GRM155R61H104KE14D"
			(at 0 0 90)
			(unlocked yes)
			(layer "B.Fab")
			(hide yes)
			(effects
				(font
					(size 1 1)
					(thickness 0.15)
				)
				(justify mirror)
			)
		)
		(property "Val" "100n"
			(at 0 0 90)
			(unlocked yes)
			(layer "B.Fab")
			(hide yes)
			(effects
				(font
					(size 1 1)
					(thickness 0.15)
				)
				(justify mirror)
			)
		)
		(property "License" "Apache-2.0"
			(at 0 0 90)
			(unlocked yes)
			(layer "B.Fab")
			(hide yes)
			(effects
				(font
					(size 1 1)
					(thickness 0.15)
				)
				(justify mirror)
			)
		)
		(property "Author" "Antmicro"
			(at 0 0 90)
			(unlocked yes)
			(layer "B.Fab")
			(hide yes)
			(effects
				(font
					(size 1 1)
					(thickness 0.15)
				)
				(justify mirror)
			)
		)
		(property "Voltage" "50V"
			(at 0 0 90)
			(unlocked yes)
			(layer "B.Fab")
			(hide yes)
			(effects
				(font
					(size 1 1)
					(thickness 0.15)
				)
				(justify mirror)
			)
		)
		(property "Dielectric" "X5R"
			(at 0 0 90)
			(unlocked yes)
			(layer "B.Fab")
			(hide yes)
			(effects
				(font
					(size 1 1)
					(thickness 0.15)
				)
				(justify mirror)
			)
		)
		(sheetname "/FPGA banks HP/")
		(sheetfile "fpga-hp-banks.kicad_sch")
		(attr smd)
		(fp_rect
			(start -0.95 0.45)
			(end 0.95 -0.45)
			(stroke
				(width 0.05)
				(type default)
			)
			(fill no)
			(layer "B.CrtYd")
		)
		(fp_line
			(start 0.498 -0.248)
			(end -0.5 -0.248)
			(stroke
				(width 0.15)
				(type solid)
			)
			(layer "B.Fab")
		)
		(fp_line
			(start -0.5 -0.248)
			(end -0.5 0.25)
			(stroke
				(width 0.15)
				(type solid)
			)
			(layer "B.Fab")
		)
		(fp_line
			(start 0.498 0.25)
			(end 0.498 -0.248)
			(stroke
				(width 0.15)
				(type solid)
			)
			(layer "B.Fab")
		)
		(fp_line
			(start -0.5 0.25)
			(end 0.498 0.25)
			(stroke
				(width 0.15)
				(type solid)
			)
			(layer "B.Fab")
		)
		(fp_text user "${REFERENCE}"
			(at -0.9656 -3.169 270)
			(layer "B.Fab")
			(effects
				(font
					(size 0.7 0.7)
					(thickness 0.15)
				)
				(justify left bottom mirror)
			)
		)
		(fp_text user "Author: Antmicro"
			(at -0.9656 -5.569 270)
			(layer "B.Fab")
			(effects
				(font
					(size 0.7 0.7)
					(thickness 0.15)
				)
				(justify left bottom mirror)
			)
		)
		(fp_text user "License: Apache-2.0"
			(at -0.9656 -4.369 270)
			(layer "B.Fab")
			(effects
				(font
					(size 0.7 0.7)
					(thickness 0.15)
				)
				(justify left bottom mirror)
			)
		)
		(pad "1" smd roundrect
			(at -0.5 0)
			(size 0.6 0.6)
			(layers "B.Cu" "B.Mask" "B.Paste")
			(roundrect_rratio 0.25)
			(net 536 "/FPGA banks HP/VREF_65")
			(pintype "passive")
		)
		(pad "2" smd roundrect
			(at 0.498 0 90)
			(size 0.6 0.6)
			(layers "B.Cu" "B.Mask" "B.Paste")
			(roundrect_rratio 0.25)
			(net 1 "GND")
			(pintype "passive")
		)
	)
	(footprint "antmicro-footprints:R_0402_1005Metric"
		(layer "B.Cu")
		(at 108 102.1 -90)
		(descr "Resistor SMD 0402")
		(tags "resistor SMD 0402")
		(property "Reference" "R42"
			(at -1.122484 0.772697 90)
			(layer "B.SilkS")
			(effects
				(font
					(size 0.7 0.7)
					(thickness 0.15)
				)
				(justify left bottom mirror)
			)
		)
		(property "Value" "R_330R_0402"
			(at -1.011843 -1.772047 90)
			(layer "B.Fab")
			(effects
				(font
					(size 0.7 0.7)
					(thickness 0.15)
				)
				(justify left bottom mirror)
			)
		)
		(property "Datasheet" "https://www.bourns.com/docs/product-datasheets/cr.pdf"
			(at 0 0 270)
			(layer "F.Fab")
			(hide yes)
			(effects
				(font
					(size 1.27 1.27)
					(thickness 0.15)
				)
			)
		)
		(property "Manufacturer" "Bourns"
			(at 0 0 270)
			(unlocked yes)
			(layer "B.Fab")
			(hide yes)
			(effects
				(font
					(size 1 1)
					(thickness 0.15)
				)
				(justify mirror)
			)
		)
		(property "MPN" "CR0402-FX-3300GLF"
			(at 0 0 270)
			(unlocked yes)
			(layer "B.Fab")
			(hide yes)
			(effects
				(font
					(size 1 1)
					(thickness 0.15)
				)
				(justify mirror)
			)
		)
		(property "Val" "330R"
			(at 0 0 270)
			(unlocked yes)
			(layer "B.Fab")
			(hide yes)
			(effects
				(font
					(size 1 1)
					(thickness 0.15)
				)
				(justify mirror)
			)
		)
		(property "License" "Apache-2.0"
			(at 0 0 270)
			(unlocked yes)
			(layer "B.Fab")
			(hide yes)
			(effects
				(font
					(size 1 1)
					(thickness 0.15)
				)
				(justify mirror)
			)
		)
		(property "Author" "Antmicro"
			(at 0 0 270)
			(unlocked yes)
			(layer "B.Fab")
			(hide yes)
			(effects
				(font
					(size 1 1)
					(thickness 0.15)
				)
				(justify mirror)
			)
		)
		(property "Tolerance" "1%"
			(at 0 0 270)
			(unlocked yes)
			(layer "B.Fab")
			(hide yes)
			(effects
				(font
					(size 1 1)
					(thickness 0.15)
				)
				(justify mirror)
			)
		)
		(sheetname "/FPGA banks HD/")
		(sheetfile "fpga-hd-banks.kicad_sch")
		(attr smd)
		(fp_rect
			(start -0.925 0.47)
			(end 0.925 -0.47)
			(stroke
				(width 0.05)
				(type default)
			)
			(fill no)
			(layer "B.CrtYd")
		)
		(fp_rect
			(start -0.5 0.25)
			(end 0.5 -0.25)
			(stroke
				(width 0.15)
				(type solid)
			)
			(fill no)
			(layer "B.Fab")
		)
		(fp_text user "License: Apache-2.0"
			(at -0.95 -5.169 90)
			(layer "B.Fab")
			(effects
				(font
					(size 0.7 0.7)
					(thickness 0.15)
				)
				(justify left bottom mirror)
			)
		)
		(fp_text user "${REFERENCE}"
			(at -0.95 -3.168 90)
			(layer "B.Fab")
			(effects
				(font
					(size 0.7 0.7)
					(thickness 0.15)
				)
				(justify left bottom mirror)
			)
		)
		(fp_text user "Author: Antmicro"
			(at -0.95 -4.169 90)
			(layer "B.Fab")
			(effects
				(font
					(size 0.7 0.7)
					(thickness 0.15)
				)
				(justify left bottom mirror)
			)
		)
		(pad "1" smd roundrect
			(at -0.48 0 270)
			(size 0.59 0.64)
			(layers "B.Cu" "B.Mask" "B.Paste")
			(roundrect_rratio 0.25)
			(net 231 "Net-(D6-A)")
			(pintype "passive")
		)
		(pad "2" smd roundrect
			(at 0.48 0 270)
			(size 0.59 0.64)
			(layers "B.Cu" "B.Mask" "B.Paste")
			(roundrect_rratio 0.25)
			(net 274 "Net-(Q6-D)")
			(pintype "passive")
		)
	)
	(footprint "antmicro-footprints:C_0402_1005Metric_EIA"
		(layer "B.Cu")
		(at 193 156.499999 90)
		(descr "Capacitor SMD 0402 (1005 Metric), square (rectangular) end terminal, IPC_7351 nominal, (Body size source: IPC-SM-782 page 76, https://www.pcb-3d.com/wordpress/wp-content/uploads/ipc-sm-782a_amendment_1_and_2.pdf)")
		(tags "capacitor 0402")
		(property "Reference" "C92"
			(at 9.849999 -30.7 90)
			(layer "B.SilkS")
			(effects
				(font
					(size 0.7 0.7)
					(thickness 0.15)
				)
				(justify right bottom mirror)
			)
		)
		(property "Value" "C_1u_25V_0402"
			(at 0 -1.169 90)
			(layer "B.Fab")
			(effects
				(font
					(size 0.7 0.7)
					(thickness 0.15)
				)
				(justify right bottom mirror)
			)
		)
		(property "Datasheet" "https://www.murata.com/products/productdetail?partno=GRM155R61E105KE11%23"
			(at 0 0 90)
			(layer "F.Fab")
			(hide yes)
			(effects
				(font
					(size 1.27 1.27)
					(thickness 0.15)
				)
			)
		)
		(property "MPN" "GRM155R61E105KE11J"
			(at 0 0 90)
			(unlocked yes)
			(layer "B.Fab")
			(hide yes)
			(effects
				(font
					(size 1 1)
					(thickness 0.15)
				)
				(justify mirror)
			)
		)
		(property "Manufacturer" "Murata"
			(at 0 0 90)
			(unlocked yes)
			(layer "B.Fab")
			(hide yes)
			(effects
				(font
					(size 1 1)
					(thickness 0.15)
				)
				(justify mirror)
			)
		)
		(property "License" "Apache-2.0"
			(at 0 0 90)
			(unlocked yes)
			(layer "B.Fab")
			(hide yes)
			(effects
				(font
					(size 1 1)
					(thickness 0.15)
				)
				(justify mirror)
			)
		)
		(property "Author" "Antmicro"
			(at 0 0 90)
			(unlocked yes)
			(layer "B.Fab")
			(hide yes)
			(effects
				(font
					(size 1 1)
					(thickness 0.15)
				)
				(justify mirror)
			)
		)
		(property "Val" "1u"
			(at 0 0 90)
			(unlocked yes)
			(layer "B.Fab")
			(hide yes)
			(effects
				(font
					(size 1 1)
					(thickness 0.15)
				)
				(justify mirror)
			)
		)
		(property "Voltage" "25V"
			(at 0 0 90)
			(unlocked yes)
			(layer "B.Fab")
			(hide yes)
			(effects
				(font
					(size 1 1)
					(thickness 0.15)
				)
				(justify mirror)
			)
		)
		(property "Dielectric" "X5R"
			(at 0 0 90)
			(unlocked yes)
			(layer "B.Fab")
			(hide yes)
			(effects
				(font
					(size 1 1)
					(thickness 0.15)
				)
				(justify mirror)
			)
		)
		(sheetname "/FPGA power/")
		(sheetfile "fpga-power.kicad_sch")
		(attr smd)
		(fp_rect
			(start -0.95 0.45)
			(end 0.95 -0.45)
			(stroke
				(width 0.05)
				(type default)
			)
			(fill no)
			(layer "B.CrtYd")
		)
		(fp_line
			(start 0.498 -0.248)
			(end -0.5 -0.248)
			(stroke
				(width 0.15)
				(type solid)
			)
			(layer "B.Fab")
		)
		(fp_line
			(start -0.5 -0.248)
			(end -0.5 0.25)
			(stroke
				(width 0.15)
				(type solid)
			)
			(layer "B.Fab")
		)
		(fp_line
			(start 0.498 0.25)
			(end 0.498 -0.248)
			(stroke
				(width 0.15)
				(type solid)
			)
			(layer "B.Fab")
		)
		(fp_line
			(start -0.5 0.25)
			(end 0.498 0.25)
			(stroke
				(width 0.15)
				(type solid)
			)
			(layer "B.Fab")
		)
		(fp_text user "Author: Antmicro"
			(at -0.9656 -5.569 270)
			(layer "B.Fab")
			(effects
				(font
					(size 0.7 0.7)
					(thickness 0.15)
				)
				(justify left bottom mirror)
			)
		)
		(fp_text user "${REFERENCE}"
			(at -0.9656 -3.169 270)
			(layer "B.Fab")
			(effects
				(font
					(size 0.7 0.7)
					(thickness 0.15)
				)
				(justify left bottom mirror)
			)
		)
		(fp_text user "License: Apache-2.0"
			(at -0.9656 -4.369 270)
			(layer "B.Fab")
			(effects
				(font
					(size 0.7 0.7)
					(thickness 0.15)
				)
				(justify left bottom mirror)
			)
		)
		(pad "1" smd roundrect
			(at -0.5 0)
			(size 0.6 0.6)
			(layers "B.Cu" "B.Mask" "B.Paste")
			(roundrect_rratio 0.25)
			(net 1 "GND")
			(pintype "passive")
		)
		(pad "2" smd roundrect
			(at 0.498 0 90)
			(size 0.6 0.6)
			(layers "B.Cu" "B.Mask" "B.Paste")
			(roundrect_rratio 0.25)
			(net 553 "+0V85")
			(pintype "passive")
		)
	)
	(footprint "antmicro-footprints:C_0805_2012Metric"
		(layer "B.Cu")
		(at 203.5 158.4 90)
		(descr "Capacitor SMD 0805")
		(tags "capacitor SMD 0805")
		(property "Reference" "C241"
			(at -1.22 1.91 90)
			(layer "B.SilkS")
			(effects
				(font
					(size 0.7 0.7)
					(thickness 0.15)
				)
				(justify right bottom mirror)
			)
		)
		(property "Value" "C_100u_0805"
			(at -2.055717 -1.963152 90)
			(layer "B.Fab")
			(effects
				(font
					(size 0.7 0.7)
					(thickness 0.15)
				)
				(justify right bottom mirror)
			)
		)
		(property "Datasheet" "https://www.murata.com/products/productdetail?partno=GRM21BR60J107ME15%23"
			(at 0 0 90)
			(layer "F.Fab")
			(hide yes)
			(effects
				(font
					(size 1.27 1.27)
					(thickness 0.15)
				)
			)
		)
		(property "MPN" "GRM21BR60J107ME15L"
			(at 0 0 90)
			(unlocked yes)
			(layer "B.Fab")
			(hide yes)
			(effects
				(font
					(size 1 1)
					(thickness 0.15)
				)
				(justify mirror)
			)
		)
		(property "Manufacturer" "Murata"
			(at 0 0 90)
			(unlocked yes)
			(layer "B.Fab")
			(hide yes)
			(effects
				(font
					(size 1 1)
					(thickness 0.15)
				)
				(justify mirror)
			)
		)
		(property "License" "Apache-2.0"
			(at 0 0 90)
			(unlocked yes)
			(layer "B.Fab")
			(hide yes)
			(effects
				(font
					(size 1 1)
					(thickness 0.15)
				)
				(justify mirror)
			)
		)
		(property "Author" "Antmicro"
			(at 0 0 90)
			(unlocked yes)
			(layer "B.Fab")
			(hide yes)
			(effects
				(font
					(size 1 1)
					(thickness 0.15)
				)
				(justify mirror)
			)
		)
		(property "Val" "100u"
			(at 0 0 90)
			(unlocked yes)
			(layer "B.Fab")
			(hide yes)
			(effects
				(font
					(size 1 1)
					(thickness 0.15)
				)
				(justify mirror)
			)
		)
		(property "Voltage" ""
			(at 0 0 90)
			(unlocked yes)
			(layer "B.Fab")
			(hide yes)
			(effects
				(font
					(size 1 1)
					(thickness 0.15)
				)
				(justify mirror)
			)
		)
		(property "Dielectric" ""
			(at 0 0 90)
			(unlocked yes)
			(layer "B.Fab")
			(hide yes)
			(effects
				(font
					(size 1 1)
					(thickness 0.15)
				)
				(justify mirror)
			)
		)
		(property "Public" "False"
			(at 0 0 90)
			(unlocked yes)
			(layer "B.Fab")
			(hide yes)
			(effects
				(font
					(size 1 1)
					(thickness 0.15)
				)
				(justify mirror)
			)
		)
		(sheetname "/FPGA power/")
		(sheetfile "fpga-power.kicad_sch")
		(attr smd)
		(fp_line
			(start -0.3 -0.7)
			(end 0.3 -0.7)
			(stroke
				(width 0.15)
				(type solid)
			)
			(layer "B.SilkS")
		)
		(fp_line
			(start -0.3 0.7)
			(end 0.3 0.7)
			(stroke
				(width 0.15)
				(type solid)
			)
			(layer "B.SilkS")
		)
		(fp_rect
			(start 1.95 0.9)
			(end -1.95 -0.9)
			(stroke
				(width 0.05)
				(type default)
			)
			(fill no)
			(layer "B.CrtYd")
		)
		(fp_rect
			(start -0.95 0.675)
			(end 0.95 -0.675)
			(stroke
				(width 0.15)
				(type solid)
			)
			(fill no)
			(layer "B.Fab")
		)
		(fp_text user "License: Apache-2.0"
			(at -1.9 -4.947 270)
			(layer "B.Fab")
			(effects
				(font
					(size 0.7 0.7)
					(thickness 0.15)
				)
				(justify left bottom mirror)
			)
		)
		(fp_text user "Author: Antmicro"
			(at -1.9 -5.947 270)
			(layer "B.Fab")
			(effects
				(font
					(size 0.7 0.7)
					(thickness 0.15)
				)
				(justify left bottom mirror)
			)
		)
		(fp_text user "${REFERENCE}"
			(at -1.9 -3.947 270)
			(layer "B.Fab")
			(effects
				(font
					(size 0.7 0.7)
					(thickness 0.15)
				)
				(justify left bottom mirror)
			)
		)
		(pad "1" smd roundrect
			(at -1.1 0 90)
			(size 1.2 1.3)
			(layers "B.Cu" "B.Mask" "B.Paste")
			(roundrect_rratio 0.25)
			(net 1 "GND")
			(pintype "passive")
		)
		(pad "2" smd roundrect
			(at 1.1 0 90)
			(size 1.2 1.3)
			(layers "B.Cu" "B.Mask" "B.Paste")
			(roundrect_rratio 0.25)
			(net 553 "+0V85")
			(pintype "passive")
		)
	)
	(footprint "antmicro-footprints:R_0402_1005Metric"
		(layer "B.Cu")
		(at 188.4 103.2 180)
		(descr "Resistor SMD 0402")
		(tags "resistor SMD 0402")
		(property "Reference" "R25"
			(at -3.13 -0.41 0)
			(layer "B.SilkS")
			(effects
				(font
					(size 0.7 0.7)
					(thickness 0.15)
				)
				(justify left bottom mirror)
			)
		)
		(property "Value" "R_47k_0402"
			(at -1.011843 -1.772047 0)
			(layer "B.Fab")
			(effects
				(font
					(size 0.7 0.7)
					(thickness 0.15)
				)
				(justify left bottom mirror)
			)
		)
		(property "Datasheet" "https://www.bourns.com/docs/product-datasheets/cr.pdf"
			(at 0 0 180)
			(layer "F.Fab")
			(hide yes)
			(effects
				(font
					(size 1.27 1.27)
					(thickness 0.15)
				)
			)
		)
		(property "MPN" "CR0402-FX-4702GLF"
			(at 0 0 180)
			(unlocked yes)
			(layer "B.Fab")
			(hide yes)
			(effects
				(font
					(size 1 1)
					(thickness 0.15)
				)
				(justify mirror)
			)
		)
		(property "Manufacturer" "Bourns"
			(at 0 0 180)
			(unlocked yes)
			(layer "B.Fab")
			(hide yes)
			(effects
				(font
					(size 1 1)
					(thickness 0.15)
				)
				(justify mirror)
			)
		)
		(property "License" "Apache-2.0"
			(at 0 0 180)
			(unlocked yes)
			(layer "B.Fab")
			(hide yes)
			(effects
				(font
					(size 1 1)
					(thickness 0.15)
				)
				(justify mirror)
			)
		)
		(property "Author" "Antmicro"
			(at 0 0 180)
			(unlocked yes)
			(layer "B.Fab")
			(hide yes)
			(effects
				(font
					(size 1 1)
					(thickness 0.15)
				)
				(justify mirror)
			)
		)
		(property "Val" "47k"
			(at 0 0 180)
			(unlocked yes)
			(layer "B.Fab")
			(hide yes)
			(effects
				(font
					(size 1 1)
					(thickness 0.15)
				)
				(justify mirror)
			)
		)
		(property "Tolerance" "1%"
			(at 0 0 180)
			(unlocked yes)
			(layer "B.Fab")
			(hide yes)
			(effects
				(font
					(size 1 1)
					(thickness 0.15)
				)
				(justify mirror)
			)
		)
		(sheetname "/DDR5 RDIMM/")
		(sheetfile "ddr5-rdimm.kicad_sch")
		(attr smd)
		(fp_rect
			(start -0.925 0.47)
			(end 0.925 -0.47)
			(stroke
				(width 0.05)
				(type default)
			)
			(fill no)
			(layer "B.CrtYd")
		)
		(fp_rect
			(start -0.5 0.25)
			(end 0.5 -0.25)
			(stroke
				(width 0.15)
				(type solid)
			)
			(fill no)
			(layer "B.Fab")
		)
		(fp_text user "Author: Antmicro"
			(at -0.95 -4.169 0)
			(layer "B.Fab")
			(effects
				(font
					(size 0.7 0.7)
					(thickness 0.15)
				)
				(justify left bottom mirror)
			)
		)
		(fp_text user "License: Apache-2.0"
			(at -0.95 -5.169 0)
			(layer "B.Fab")
			(effects
				(font
					(size 0.7 0.7)
					(thickness 0.15)
				)
				(justify left bottom mirror)
			)
		)
		(fp_text user "${REFERENCE}"
			(at -0.95 -3.168 0)
			(layer "B.Fab")
			(effects
				(font
					(size 0.7 0.7)
					(thickness 0.15)
				)
				(justify left bottom mirror)
			)
		)
		(pad "1" smd roundrect
			(at -0.48 0 180)
			(size 0.59 0.64)
			(layers "B.Cu" "B.Mask" "B.Paste")
			(roundrect_rratio 0.25)
			(net 703 "/DDR5 RDIMM/VSS_DET1")
			(pintype "passive")
		)
		(pad "2" smd roundrect
			(at 0.48 0 180)
			(size 0.59 0.64)
			(layers "B.Cu" "B.Mask" "B.Paste")
			(roundrect_rratio 0.25)
			(net 151 "+3V3")
			(pintype "passive")
		)
	)
)
